(kicad_pcb
	(version 20260206)
	(generator "pcbnew")
	(generator_version "10.0")
	(general
		(thickness 1.6)
		(legacy_teardrops no)
	)
	(paper "A4")
	(title_block
		(title "03242023_DA0F0TMBIJ0_F0T_Motherboard_J_brd_V01_OCP.brd")
		(comment 1 "Grand Teton / footprints 2920-2924 of 6105")
	)
	(layers
		(0 "F.Cu" signal "TOP")
		(4 "In1.Cu" signal "GND")
		(6 "In2.Cu" signal "IN1")
		(8 "In3.Cu" signal "GND1")
		(10 "In4.Cu" signal "IN2")
		(12 "In5.Cu" signal "GND2")
		(14 "In6.Cu" signal "IN3")
		(16 "In7.Cu" signal "GND3")
		(18 "In8.Cu" signal "VCC")
		(20 "In9.Cu" signal "VCC1")
		(22 "In10.Cu" signal "GND4")
		(24 "In11.Cu" signal "IN4")
		(26 "In12.Cu" signal "GND5")
		(28 "In13.Cu" signal "IN5")
		(30 "In14.Cu" signal "GND6")
		(32 "In15.Cu" signal "IN6")
		(34 "In16.Cu" signal "GND7")
		(2 "B.Cu" signal "BOTTOM")
		(9 "F.Adhes" user "F.Adhesive")
		(11 "B.Adhes" user "B.Adhesive")
		(13 "F.Paste" user "Package Geometry/Pastemask Top")
		(15 "B.Paste" user "Package Geometry/Pastemask Bottom")
		(5 "F.SilkS" user "Ref Des/Silkscreen Top")
		(7 "B.SilkS" user "Ref Des/Silkscreen Bottom")
		(1 "F.Mask" user "Board Geometry/Soldermask Top")
		(3 "B.Mask" user "Board Geometry/Soldermask Bottom")
		(17 "Dwgs.User" user "User.Drawings")
		(19 "Cmts.User" user "User.Comments")
		(21 "Eco1.User" user "User.Eco1")
		(23 "Eco2.User" user "User.Eco2")
		(25 "Edge.Cuts" user "Board Geometry/Outline")
		(27 "Margin" user)
		(31 "F.CrtYd" user "Package Geometry/Place Bound Top")
		(29 "B.CrtYd" user "Package Geometry/Place Bound Bottom")
		(35 "F.Fab" user "Ref Des/Assembly Top")
		(33 "B.Fab" user "Ref Des/Assembly Bottom")
	)
	(footprint ""
		(layer "F.Cu")
		(at 160.83788 -131.155948 90)
		(property "Reference" "Q53"
			(at 3.93573 -0.59436 0)
			(unlocked yes)
			(layer "F.SilkS")
			(effects
				(font
					(size 0.7874 0.5842)
					(thickness 0.1524)
				)
				(justify left)
			)
		)
		(property "Value" ""
			(at 0 0 90)
			(layer "F.Fab")
			(effects
				(font
					(size 1.27 1.27)
				)
			)
		)
		(duplicate_pad_numbers_are_jumpers no)
		(fp_line
			(start 1.603248 -1.500124)
			(end 1.603248 1.500124)
			(stroke
				(width 0.1524)
				(type default)
			)
			(layer "F.SilkS")
		)
		(fp_line
			(start -1.603248 -1.500124)
			(end 1.603248 -1.500124)
			(stroke
				(width 0.1524)
				(type default)
			)
			(layer "F.SilkS")
		)
		(fp_line
			(start 1.603248 1.500124)
			(end -1.603248 1.500124)
			(stroke
				(width 0.1524)
				(type default)
			)
			(layer "F.SilkS")
		)
		(fp_line
			(start -1.603248 1.500124)
			(end -1.603248 -1.500124)
			(stroke
				(width 0.1524)
				(type default)
			)
			(layer "F.SilkS")
		)
		(fp_line
			(start 0.700024 -1.500124)
			(end -0.700024 -1.500124)
			(stroke
				(width 0.1)
				(type default)
			)
			(layer "F.Fab")
		)
		(fp_line
			(start -0.700024 -1.500124)
			(end -0.700024 -1.169924)
			(stroke
				(width 0.1)
				(type default)
			)
			(layer "F.Fab")
		)
		(fp_line
			(start -0.700024 -1.169924)
			(end -1.249934 -1.169924)
			(stroke
				(width 0.1)
				(type default)
			)
			(layer "F.Fab")
		)
		(fp_line
			(start -1.249934 -1.169924)
			(end -1.249934 -0.729996)
			(stroke
				(width 0.1)
				(type default)
			)
			(layer "F.Fab")
		)
		(fp_line
			(start -0.6985 -0.729996)
			(end -0.6985 0.729996)
			(stroke
				(width 0.1)
				(type default)
			)
			(layer "F.Fab")
		)
		(fp_line
			(start -1.249934 -0.729996)
			(end -0.6985 -0.729996)
			(stroke
				(width 0.1)
				(type default)
			)
			(layer "F.Fab")
		)
		(fp_line
			(start 1.249934 -0.219964)
			(end 0.700024 -0.219964)
			(stroke
				(width 0.1)
				(type default)
			)
			(layer "F.Fab")
		)
		(fp_line
			(start 0.700024 -0.219964)
			(end 0.700024 -1.500124)
			(stroke
				(width 0.1)
				(type default)
			)
			(layer "F.Fab")
		)
		(fp_line
			(start 1.249934 0.219964)
			(end 1.249934 -0.219964)
			(stroke
				(width 0.1)
				(type default)
			)
			(layer "F.Fab")
		)
		(fp_line
			(start 0.700024 0.219964)
			(end 1.249934 0.219964)
			(stroke
				(width 0.1)
				(type default)
			)
			(layer "F.Fab")
		)
		(fp_line
			(start -0.6985 0.729996)
			(end -1.249934 0.729996)
			(stroke
				(width 0.1)
				(type default)
			)
			(layer "F.Fab")
		)
		(fp_line
			(start -1.249934 0.729996)
			(end -1.249934 1.169924)
			(stroke
				(width 0.1)
				(type default)
			)
			(layer "F.Fab")
		)
		(fp_line
			(start -0.700024 1.169924)
			(end -0.700024 1.500124)
			(stroke
				(width 0.1)
				(type default)
			)
			(layer "F.Fab")
		)
		(fp_line
			(start -1.249934 1.169924)
			(end -0.700024 1.169924)
			(stroke
				(width 0.1)
				(type default)
			)
			(layer "F.Fab")
		)
		(fp_line
			(start 0.700024 1.500124)
			(end 0.700024 0.219964)
			(stroke
				(width 0.1)
				(type default)
			)
			(layer "F.Fab")
		)
		(fp_line
			(start -0.700024 1.500124)
			(end 0.700024 1.500124)
			(stroke
				(width 0.1)
				(type default)
			)
			(layer "F.Fab")
		)
		(fp_rect
			(start -0.700024 1.500124)
			(end 0.700024 -1.500124)
			(stroke
				(width 0)
				(type default)
			)
			(fill no)
			(layer "F.Fab")
		)
		(pad "D" smd rect
			(at 0.999998 0)
			(size 0.8128 0.9144)
			(layers "F.Cu" "F.Mask" "F.Paste")
			(net "PWRGD_P3V3_AUX_R2")
		)
		(pad "G" smd rect
			(at -0.999998 -0.94996)
			(size 0.8128 0.9144)
			(layers "F.Cu" "F.Mask" "F.Paste")
			(net "PWRGD_P3V3_AUX")
		)
		(pad "S" smd rect
			(at -0.999998 0.94996)
			(size 0.8128 0.9144)
			(layers "F.Cu" "F.Mask" "F.Paste")
			(net "GND")
		)
	)
	(footprint ""
		(layer "F.Cu")
		(at 103.103426 -409.57754 90)
		(property "Reference" "C2076"
			(at 0 0 90)
			(layer "F.SilkS")
			(hide yes)
			(effects
				(font
					(size 1.27 1.27)
				)
			)
		)
		(property "Value" ""
			(at 0 0 90)
			(layer "F.Fab")
			(effects
				(font
					(size 1.27 1.27)
				)
			)
		)
		(duplicate_pad_numbers_are_jumpers no)
		(fp_line
			(start 0.299974 -0.150114)
			(end 0.299974 0.150114)
			(stroke
				(width 0.1)
				(type default)
			)
			(layer "F.Fab")
		)
		(fp_line
			(start -0.299974 -0.150114)
			(end 0.299974 -0.150114)
			(stroke
				(width 0.1)
				(type default)
			)
			(layer "F.Fab")
		)
		(fp_line
			(start 0.299974 0.150114)
			(end -0.299974 0.150114)
			(stroke
				(width 0.1)
				(type default)
			)
			(layer "F.Fab")
		)
		(fp_line
			(start -0.299974 0.150114)
			(end -0.299974 -0.150114)
			(stroke
				(width 0.1)
				(type default)
			)
			(layer "F.Fab")
		)
		(pad "1" smd rect
			(at -0.2667 0 90)
			(size 0.3048 0.381)
			(layers "F.Cu" "F.Mask" "F.Paste")
			(net "P3E_PCH_NVS_TX_DN<0>")
		)
		(pad "2" smd rect
			(at 0.2667 0 90)
			(size 0.3048 0.381)
			(layers "F.Cu" "F.Mask" "F.Paste")
			(net "P3E_PCH_NVS_TX_C_DN<0>")
		)
		(zone
			(layer "In1.Cu")
			(hatch none 0.5)
			(connect_pads
				(clearance 0)
			)
			(min_thickness 0.25)
			(keepout
				(tracks not_allowed)
				(vias allowed)
				(pads allowed)
				(copperpour not_allowed)
				(footprints allowed)
			)
			(placement
				(enabled no)
				(sheetname "")
			)
			(fill
				(thermal_gap 0.5)
				(thermal_bridge_width 0.5)
				(island_removal_mode 0)
			)
			(polygon
				(pts
					(arc
						(start 103.344726 -409.71724)
						(mid 103.322408 -409.663358)
						(end 103.268526 -409.64104)
					)
					(arc
						(start 102.938326 -409.64104)
						(mid 102.884444 -409.663358)
						(end 102.862126 -409.71724)
					)
					(arc
						(start 102.862126 -409.97124)
						(mid 102.884444 -410.025122)
						(end 102.938326 -410.04744)
					)
					(arc
						(start 103.268526 -410.04744)
						(mid 103.322408 -410.025122)
						(end 103.344726 -409.97124)
					)
				)
			)
		)
		(zone
			(layer "In1.Cu")
			(hatch none 0.5)
			(connect_pads
				(clearance 0)
			)
			(min_thickness 0.25)
			(keepout
				(tracks not_allowed)
				(vias allowed)
				(pads allowed)
				(copperpour not_allowed)
				(footprints allowed)
			)
			(placement
				(enabled no)
				(sheetname "")
			)
			(fill
				(thermal_gap 0.5)
				(thermal_bridge_width 0.5)
				(island_removal_mode 0)
			)
			(polygon
				(pts
					(arc
						(start 103.344726 -409.18384)
						(mid 103.322408 -409.129958)
						(end 103.268526 -409.10764)
					)
					(arc
						(start 102.938326 -409.10764)
						(mid 102.884444 -409.129958)
						(end 102.862126 -409.18384)
					)
					(arc
						(start 102.862126 -409.43784)
						(mid 102.884444 -409.491722)
						(end 102.938326 -409.51404)
					)
					(arc
						(start 103.268526 -409.51404)
						(mid 103.322408 -409.491722)
						(end 103.344726 -409.43784)
					)
				)
			)
		)
	)
	(footprint ""
		(layer "F.Cu")
		(at 147.08378 -125.275848 180)
		(property "Reference" "R3156"
			(at 0 0 180)
			(layer "F.SilkS")
			(hide yes)
			(effects
				(font
					(size 1.27 1.27)
				)
			)
		)
		(property "Value" ""
			(at 0 0 180)
			(layer "F.Fab")
			(effects
				(font
					(size 1.27 1.27)
				)
			)
		)
		(duplicate_pad_numbers_are_jumpers no)
		(fp_line
			(start 0.7874 0.4064)
			(end -0.7874 0.4064)
			(stroke
				(width 0.1524)
				(type default)
			)
			(layer "F.SilkS")
		)
		(fp_line
			(start 0.7874 -0.4064)
			(end 0.7874 0.4064)
			(stroke
				(width 0.1524)
				(type default)
			)
			(layer "F.SilkS")
		)
		(fp_line
			(start -0.7874 0.4064)
			(end -0.7874 -0.4064)
			(stroke
				(width 0.1524)
				(type default)
			)
			(layer "F.SilkS")
		)
		(fp_line
			(start -0.7874 -0.4064)
			(end 0.7874 -0.4064)
			(stroke
				(width 0.1524)
				(type default)
			)
			(layer "F.SilkS")
		)
		(fp_line
			(start 0.67945 0.3048)
			(end 0.120396 0.3048)
			(stroke
				(width 0.1)
				(type default)
			)
			(layer "F.Fab")
		)
		(fp_line
			(start 0.67945 -0.3048)
			(end 0.67945 0.3048)
			(stroke
				(width 0.1)
				(type default)
			)
			(layer "F.Fab")
		)
		(fp_line
			(start 0.12065 -0.2794)
			(end 0.12065 -0.3048)
			(stroke
				(width 0.1)
				(type default)
			)
			(layer "F.Fab")
		)
		(fp_line
			(start 0.12065 -0.3048)
			(end 0.67945 -0.3048)
			(stroke
				(width 0.1)
				(type default)
			)
			(layer "F.Fab")
		)
		(fp_line
			(start 0.120396 0.3048)
			(end 0.120396 0.2794)
			(stroke
				(width 0.1)
				(type default)
			)
			(layer "F.Fab")
		)
		(fp_line
			(start 0.120396 0.2794)
			(end -0.12065 0.2794)
			(stroke
				(width 0.1)
				(type default)
			)
			(layer "F.Fab")
		)
		(fp_line
			(start -0.12065 0.3048)
			(end -0.67945 0.3048)
			(stroke
				(width 0.1)
				(type default)
			)
			(layer "F.Fab")
		)
		(fp_line
			(start -0.12065 0.2794)
			(end -0.12065 0.3048)
			(stroke
				(width 0.1)
				(type default)
			)
			(layer "F.Fab")
		)
		(fp_line
			(start -0.12065 -0.2794)
			(end 0.12065 -0.2794)
			(stroke
				(width 0.1)
				(type default)
			)
			(layer "F.Fab")
		)
		(fp_line
			(start -0.12065 -0.305054)
			(end -0.12065 -0.2794)
			(stroke
				(width 0.1)
				(type default)
			)
			(layer "F.Fab")
		)
		(fp_line
			(start -0.67945 0.3048)
			(end -0.67945 -0.305054)
			(stroke
				(width 0.1)
				(type default)
			)
			(layer "F.Fab")
		)
		(fp_line
			(start -0.67945 -0.305054)
			(end -0.12065 -0.305054)
			(stroke
				(width 0.1)
				(type default)
			)
			(layer "F.Fab")
		)
		(pad "1" smd circle
			(at -0.40005 0 180)
			(size 0 0)
			(layers "F.Cu" "F.Mask" "F.Paste")
			(net "SMB_PEHPCPU1_LVC3_SCL")
		)
		(pad "2" smd circle
			(at 0.40005 0 180)
			(size 0 0)
			(layers "F.Cu" "F.Mask" "F.Paste")
			(net "SMB_PEHPCPU1_LVC3_R3_SCL")
		)
	)
	(footprint ""
		(layer "F.Cu")
		(at 522.584426 2.295652 -90)
		(property "Reference" "X13"
			(at -1.331976 3.323336 90)
			(unlocked yes)
			(layer "F.SilkS")
			(effects
				(font
					(size 0.7874 0.5842)
					(thickness 0.1524)
				)
				(justify left)
			)
		)
		(property "Value" ""
			(at 0 0 270)
			(layer "F.Fab")
			(effects
				(font
					(size 1.27 1.27)
				)
			)
		)
		(property "Device Type" "TP_TDR_4P_FTS_MPKT4_H025P0200_I"
			(at 1.30175 1.27 0)
			(unlocked yes)
			(layer "F.Fab")
			(hide yes)
			(effects
				(font
					(size 0.635 0.4064)
					(thickness 0.1524)
				)
			)
		)
		(property "User Part Number" "TP15"
			(at 1.30175 1.27 0)
			(unlocked yes)
			(layer "Cmts.User")
			(hide yes)
			(effects
				(font
					(size 0.635 0.4064)
					(thickness 0.1524)
				)
			)
		)
		(duplicate_pad_numbers_are_jumpers no)
		(fp_line
			(start 0 3.81)
			(end 2.54 3.81)
			(stroke
				(width 0.1524)
				(type default)
			)
			(layer "F.SilkS")
		)
		(fp_line
			(start 2.54 3.81)
			(end 2.54 3.6703)
			(stroke
				(width 0.1524)
				(type default)
			)
			(layer "F.SilkS")
		)
		(fp_line
			(start 0 3.175)
			(end 0 3.81)
			(stroke
				(width 0.1524)
				(type default)
			)
			(layer "F.SilkS")
		)
		(fp_line
			(start 2.54 1.4097)
			(end 2.54 1.1303)
			(stroke
				(width 0.1524)
				(type default)
			)
			(layer "F.SilkS")
		)
		(fp_line
			(start 0 0.635)
			(end 0 1.905)
			(stroke
				(width 0.1524)
				(type default)
			)
			(layer "F.SilkS")
		)
		(fp_line
			(start 2.54 -1.1303)
			(end 2.54 -1.27)
			(stroke
				(width 0.1524)
				(type default)
			)
			(layer "F.SilkS")
		)
		(fp_line
			(start 0 -1.27)
			(end 0 -0.635)
			(stroke
				(width 0.1524)
				(type default)
			)
			(layer "F.SilkS")
		)
		(fp_line
			(start 2.54 -1.27)
			(end 0 -1.27)
			(stroke
				(width 0.1524)
				(type default)
			)
			(layer "F.SilkS")
		)
		(fp_poly
			(pts
				(xy -1.447292 0.108966) (xy -2.971292 0.870966) (xy -2.971292 -0.653034)
			)
			(stroke
				(width 0)
				(type default)
			)
			(fill yes)
			(layer "F.SilkS")
		)
		(fp_line
			(start 0 3.81)
			(end 2.54 3.81)
			(stroke
				(width 0.1)
				(type default)
			)
			(layer "F.Fab")
		)
		(fp_line
			(start 2.54 3.81)
			(end 2.54 -1.27)
			(stroke
				(width 0.1)
				(type default)
			)
			(layer "F.Fab")
		)
		(fp_line
			(start 0 -1.27)
			(end 0 3.81)
			(stroke
				(width 0.1)
				(type default)
			)
			(layer "F.Fab")
		)
		(fp_line
			(start 2.54 -1.27)
			(end 0 -1.27)
			(stroke
				(width 0.1)
				(type default)
			)
			(layer "F.Fab")
		)
		(fp_poly
			(pts
				(xy -0.761746 0) (xy -2.285746 -0.762) (xy -2.285746 0.762)
			)
			(stroke
				(width 0)
				(type default)
			)
			(fill yes)
			(layer "F.Fab")
		)
		(pad "1" thru_hole circle
			(at 0 0 270)
			(size 1.0033 1.0033)
			(drill 0.249936)
			(layers "*.Cu" "*.Mask")
			(remove_unused_layers no)
			(net "TDR_DIFF_100_TOP_DP")
			(clearance 0.10795)
			(thermal_gap 0.10795)
			(padstack
				(mode front_inner_back)
				(layer "Inner"
					(shape circle)
					(size 0.8001 0.8001)
					(clearance 0.1524)
				)
				(layer "B.Cu"
					(shape circle)
					(size 1.0033 1.0033)
					(clearance 0.10795)
				)
			)
		)
		(pad "2" thru_hole circle
			(at 2.54 0 270)
			(size 1.9939 1.9939)
			(drill 0.249936)
			(layers "*.Cu" "*.Mask")
			(remove_unused_layers no)
			(net "T1_GND")
			(clearance 0.10795)
			(thermal_gap 0.10795)
			(padstack
				(mode front_inner_back)
				(layer "Inner"
					(shape circle)
					(size 0.8001 0.8001)
					(clearance 0.1524)
				)
				(layer "B.Cu"
					(shape circle)
					(size 1.9939 1.9939)
					(clearance 0.10795)
				)
			)
		)
		(pad "3" thru_hole circle
			(at 2.54 2.54 270)
			(size 1.9939 1.9939)
			(drill 0.249936)
			(layers "*.Cu" "*.Mask")
			(remove_unused_layers no)
			(net "T1_GND")
			(clearance 0.10795)
			(thermal_gap 0.10795)
			(padstack
				(mode front_inner_back)
				(layer "Inner"
					(shape circle)
					(size 0.8001 0.8001)
					(clearance 0.1524)
				)
				(layer "B.Cu"
					(shape circle)
					(size 1.9939 1.9939)
					(clearance 0.10795)
				)
			)
		)
		(pad "4" thru_hole circle
			(at 0 2.54 270)
			(size 1.0033 1.0033)
			(drill 0.249936)
			(layers "*.Cu" "*.Mask")
			(remove_unused_layers no)
			(net "TDR_DIFF_100_TOP_DN")
			(clearance 0.10795)
			(thermal_gap 0.10795)
			(padstack
				(mode front_inner_back)
				(layer "Inner"
					(shape circle)
					(size 0.8001 0.8001)
					(clearance 0.1524)
				)
				(layer "B.Cu"
					(shape circle)
					(size 1.0033 1.0033)
					(clearance 0.10795)
				)
			)
		)
	)
	(footprint ""
		(layer "F.Cu")
		(at 36.930584 -111.603282)
		(property "Reference" "C2178"
			(at 0 0 0)
			(layer "F.SilkS")
			(hide yes)
			(effects
				(font
					(size 1.27 1.27)
				)
			)
		)
		(property "Value" ""
			(at 0 0 0)
			(layer "F.Fab")
			(effects
				(font
					(size 1.27 1.27)
				)
			)
		)
		(duplicate_pad_numbers_are_jumpers no)
		(fp_line
			(start -0.7874 -0.4064)
			(end 0.7874 -0.4064)
			(stroke
				(width 0.1524)
				(type default)
			)
			(layer "F.SilkS")
		)
		(fp_line
			(start -0.7874 0.4064)
			(end -0.7874 -0.4064)
			(stroke
				(width 0.1524)
				(type default)
			)
			(layer "F.SilkS")
		)
		(fp_line
			(start 0.7874 -0.4064)
			(end 0.7874 0.4064)
			(stroke
				(width 0.1524)
				(type default)
			)
			(layer "F.SilkS")
		)
		(fp_line
			(start 0.7874 0.4064)
			(end -0.7874 0.4064)
			(stroke
				(width 0.1524)
				(type default)
			)
			(layer "F.SilkS")
		)
		(fp_line
			(start -0.67945 -0.305054)
			(end -0.12065 -0.305054)
			(stroke
				(width 0.1)
				(type default)
			)
			(layer "F.Fab")
		)
		(fp_line
			(start -0.67945 0.3048)
			(end -0.67945 -0.305054)
			(stroke
				(width 0.1)
				(type default)
			)
			(layer "F.Fab")
		)
		(fp_line
			(start -0.12065 -0.305054)
			(end -0.12065 -0.2794)
			(stroke
				(width 0.1)
				(type default)
			)
			(layer "F.Fab")
		)
		(fp_line
			(start -0.12065 -0.2794)
			(end 0.12065 -0.2794)
			(stroke
				(width 0.1)
				(type default)
			)
			(layer "F.Fab")
		)
		(fp_line
			(start -0.12065 0.2794)
			(end -0.12065 0.3048)
			(stroke
				(width 0.1)
				(type default)
			)
			(layer "F.Fab")
		)
		(fp_line
			(start -0.12065 0.3048)
			(end -0.67945 0.3048)
			(stroke
				(width 0.1)
				(type default)
			)
			(layer "F.Fab")
		)
		(fp_line
			(start 0.120396 0.2794)
			(end -0.12065 0.2794)
			(stroke
				(width 0.1)
				(type default)
			)
			(layer "F.Fab")
		)
		(fp_line
			(start 0.120396 0.3048)
			(end 0.120396 0.2794)
			(stroke
				(width 0.1)
				(type default)
			)
			(layer "F.Fab")
		)
		(fp_line
			(start 0.12065 -0.3048)
			(end 0.67945 -0.3048)
			(stroke
				(width 0.1)
				(type default)
			)
			(layer "F.Fab")
		)
		(fp_line
			(start 0.12065 -0.2794)
			(end 0.12065 -0.3048)
			(stroke
				(width 0.1)
				(type default)
			)
			(layer "F.Fab")
		)
		(fp_line
			(start 0.67945 -0.3048)
			(end 0.67945 0.3048)
			(stroke
				(width 0.1)
				(type default)
			)
			(layer "F.Fab")
		)
		(fp_line
			(start 0.67945 0.3048)
			(end 0.120396 0.3048)
			(stroke
				(width 0.1)
				(type default)
			)
			(layer "F.Fab")
		)
		(pad "1" smd circle
			(at -0.40005 0)
			(size 0 0)
			(layers "F.Cu" "F.Mask" "F.Paste")
			(net "P12V_OCP_SFF_ISENSE_TIC")
		)
		(pad "2" smd circle
			(at 0.40005 0)
			(size 0 0)
			(layers "F.Cu" "F.Mask" "F.Paste")
			(net "GND")
		)
	)
)
